# S9S_MB_2U (Grand Teton) — schematic netlist excerpt (pin names and nets, part order shuffled) for the footprints in the layout excerpt that follows; sources: Cadence DE-HDL packaged netlist, KiCad conversion of 03242023_DA0F0TMBIJ0_F0T_Motherboard_J_brd_V01_OCP.brd

R1257  Q_RES  10K 1% CHIP  pkg 0402LF  page 204 : A = P3V3_AUX ; B = PU_PCH_VRALERT_N
PC293  Q_CAP  2.2UF 10V 10% X6S  pkg C0402  page 267 : A = PVCCIN_CPU0_VDD1 ; B = GND

(kicad_pcb
	(version 20260206)
	(generator "pcbnew")
	(generator_version "10.0")
	(general
		(thickness 1.6)
		(legacy_teardrops no)
	)
	(paper "A4")
	(title_block
		(title "03242023_DA0F0TMBIJ0_F0T_Motherboard_J_brd_V01_OCP.brd")
		(comment 1 "Grand Teton / footprints 1760-1761 of 6105")
	)
	(layers
		(0 "F.Cu" signal "TOP")
		(4 "In1.Cu" signal "GND")
		(6 "In2.Cu" signal "IN1")
		(8 "In3.Cu" signal "GND1")
		(10 "In4.Cu" signal "IN2")
		(12 "In5.Cu" signal "GND2")
		(14 "In6.Cu" signal "IN3")
		(16 "In7.Cu" signal "GND3")
		(18 "In8.Cu" signal "VCC")
		(20 "In9.Cu" signal "VCC1")
		(22 "In10.Cu" signal "GND4")
		(24 "In11.Cu" signal "IN4")
		(26 "In12.Cu" signal "GND5")
		(28 "In13.Cu" signal "IN5")
		(30 "In14.Cu" signal "GND6")
		(32 "In15.Cu" signal "IN6")
		(34 "In16.Cu" signal "GND7")
		(2 "B.Cu" signal "BOTTOM")
		(9 "F.Adhes" user "F.Adhesive")
		(11 "B.Adhes" user "B.Adhesive")
		(13 "F.Paste" user "Package Geometry/Pastemask Top")
		(15 "B.Paste" user "Package Geometry/Pastemask Bottom")
		(5 "F.SilkS" user "Ref Des/Silkscreen Top")
		(7 "B.SilkS" user "Ref Des/Silkscreen Bottom")
		(1 "F.Mask" user "Board Geometry/Soldermask Top")
		(3 "B.Mask" user "Board Geometry/Soldermask Bottom")
		(17 "Dwgs.User" user "User.Drawings")
		(19 "Cmts.User" user "User.Comments")
		(21 "Eco1.User" user "User.Eco1")
		(23 "Eco2.User" user "User.Eco2")
		(25 "Edge.Cuts" user "Board Geometry/Outline")
		(27 "Margin" user)
		(31 "F.CrtYd" user "Package Geometry/Place Bound Top")
		(29 "B.CrtYd" user "Package Geometry/Place Bound Bottom")
		(35 "F.Fab" user "Ref Des/Assembly Top")
		(33 "B.Fab" user "Ref Des/Assembly Bottom")
	)
	(footprint ""
		(layer "F.Cu")
		(at 341.362792 -336.192368 90)
		(property "Reference" "PC293"
			(at 0 0 90)
			(layer "F.SilkS")
			(hide yes)
			(effects
				(font
					(size 1.27 1.27)
				)
			)
		)
		(property "Value" ""
			(at 0 0 90)
			(layer "F.Fab")
			(effects
				(font
					(size 1.27 1.27)
				)
			)
		)
		(duplicate_pad_numbers_are_jumpers no)
		(fp_line
			(start 0.7874 -0.4064)
			(end 0.7874 0.4064)
			(stroke
				(width 0.1524)
				(type default)
			)
			(layer "F.SilkS")
		)
		(fp_line
			(start -0.7874 -0.4064)
			(end 0.7874 -0.4064)
			(stroke
				(width 0.1524)
				(type default)
			)
			(layer "F.SilkS")
		)
		(fp_line
			(start 0.7874 0.4064)
			(end -0.7874 0.4064)
			(stroke
				(width 0.1524)
				(type default)
			)
			(layer "F.SilkS")
		)
		(fp_line
			(start -0.7874 0.4064)
			(end -0.7874 -0.4064)
			(stroke
				(width 0.1524)
				(type default)
			)
			(layer "F.SilkS")
		)
		(fp_line
			(start -0.12065 -0.305054)
			(end -0.12065 -0.2794)
			(stroke
				(width 0.1)
				(type default)
			)
			(layer "F.Fab")
		)
		(fp_line
			(start -0.67945 -0.305054)
			(end -0.12065 -0.305054)
			(stroke
				(width 0.1)
				(type default)
			)
			(layer "F.Fab")
		)
		(fp_line
			(start 0.67945 -0.3048)
			(end 0.67945 0.3048)
			(stroke
				(width 0.1)
				(type default)
			)
			(layer "F.Fab")
		)
		(fp_line
			(start 0.12065 -0.3048)
			(end 0.67945 -0.3048)
			(stroke
				(width 0.1)
				(type default)
			)
			(layer "F.Fab")
		)
		(fp_line
			(start 0.12065 -0.2794)
			(end 0.12065 -0.3048)
			(stroke
				(width 0.1)
				(type default)
			)
			(layer "F.Fab")
		)
		(fp_line
			(start -0.12065 -0.2794)
			(end 0.12065 -0.2794)
			(stroke
				(width 0.1)
				(type default)
			)
			(layer "F.Fab")
		)
		(fp_line
			(start 0.120396 0.2794)
			(end -0.12065 0.2794)
			(stroke
				(width 0.1)
				(type default)
			)
			(layer "F.Fab")
		)
		(fp_line
			(start -0.12065 0.2794)
			(end -0.12065 0.3048)
			(stroke
				(width 0.1)
				(type default)
			)
			(layer "F.Fab")
		)
		(fp_line
			(start 0.67945 0.3048)
			(end 0.120396 0.3048)
			(stroke
				(width 0.1)
				(type default)
			)
			(layer "F.Fab")
		)
		(fp_line
			(start 0.120396 0.3048)
			(end 0.120396 0.2794)
			(stroke
				(width 0.1)
				(type default)
			)
			(layer "F.Fab")
		)
		(fp_line
			(start -0.12065 0.3048)
			(end -0.67945 0.3048)
			(stroke
				(width 0.1)
				(type default)
			)
			(layer "F.Fab")
		)
		(fp_line
			(start -0.67945 0.3048)
			(end -0.67945 -0.305054)
			(stroke
				(width 0.1)
				(type default)
			)
			(layer "F.Fab")
		)
		(pad "1" smd circle
			(at -0.40005 0 90)
			(size 0 0)
			(layers "F.Cu" "F.Mask" "F.Paste")
			(net "PVCCIN_CPU0_VDD1")
		)
		(pad "2" smd circle
			(at 0.40005 0 90)
			(size 0 0)
			(layers "F.Cu" "F.Mask" "F.Paste")
			(net "GND")
		)
	)
	(footprint ""
		(layer "F.Cu")
		(at 309.55488 -49.494948 180)
		(property "Reference" "R1257"
			(at 0 0 180)
			(layer "F.SilkS")
			(hide yes)
			(effects
				(font
					(size 1.27 1.27)
				)
			)
		)
		(property "Value" ""
			(at 0 0 180)
			(layer "F.Fab")
			(effects
				(font
					(size 1.27 1.27)
				)
			)
		)
		(duplicate_pad_numbers_are_jumpers no)
		(fp_line
			(start 0.7874 0.4064)
			(end -0.7874 0.4064)
			(stroke
				(width 0.1524)
				(type default)
			)
			(layer "F.SilkS")
		)
		(fp_line
			(start 0.7874 -0.4064)
			(end 0.7874 0.4064)
			(stroke
				(width 0.1524)
				(type default)
			)
			(layer "F.SilkS")
		)
		(fp_line
			(start -0.7874 0.4064)
			(end -0.7874 -0.4064)
			(stroke
				(width 0.1524)
				(type default)
			)
			(layer "F.SilkS")
		)
		(fp_line
			(start -0.7874 -0.4064)
			(end 0.7874 -0.4064)
			(stroke
				(width 0.1524)
				(type default)
			)
			(layer "F.SilkS")
		)
		(fp_line
			(start 0.67945 0.3048)
			(end 0.120396 0.3048)
			(stroke
				(width 0.1)
				(type default)
			)
			(layer "F.Fab")
		)
		(fp_line
			(start 0.67945 -0.3048)
			(end 0.67945 0.3048)
			(stroke
				(width 0.1)
				(type default)
			)
			(layer "F.Fab")
		)
		(fp_line
			(start 0.12065 -0.2794)
			(end 0.12065 -0.3048)
			(stroke
				(width 0.1)
				(type default)
			)
			(layer "F.Fab")
		)
		(fp_line
			(start 0.12065 -0.3048)
			(end 0.67945 -0.3048)
			(stroke
				(width 0.1)
				(type default)
			)
			(layer "F.Fab")
		)
		(fp_line
			(start 0.120396 0.3048)
			(end 0.120396 0.2794)
			(stroke
				(width 0.1)
				(type default)
			)
			(layer "F.Fab")
		)
		(fp_line
			(start 0.120396 0.2794)
			(end -0.12065 0.2794)
			(stroke
				(width 0.1)
				(type default)
			)
			(layer "F.Fab")
		)
		(fp_line
			(start -0.12065 0.3048)
			(end -0.67945 0.3048)
			(stroke
				(width 0.1)
				(type default)
			)
			(layer "F.Fab")
		)
		(fp_line
			(start -0.12065 0.2794)
			(end -0.12065 0.3048)
			(stroke
				(width 0.1)
				(type default)
			)
			(layer "F.Fab")
		)
		(fp_line
			(start -0.12065 -0.2794)
			(end 0.12065 -0.2794)
			(stroke
				(width 0.1)
				(type default)
			)
			(layer "F.Fab")
		)
		(fp_line
			(start -0.12065 -0.305054)
			(end -0.12065 -0.2794)
			(stroke
				(width 0.1)
				(type default)
			)
			(layer "F.Fab")
		)
		(fp_line
			(start -0.67945 0.3048)
			(end -0.67945 -0.305054)
			(stroke
				(width 0.1)
				(type default)
			)
			(layer "F.Fab")
		)
		(fp_line
			(start -0.67945 -0.305054)
			(end -0.12065 -0.305054)
			(stroke
				(width 0.1)
				(type default)
			)
			(layer "F.Fab")
		)
		(pad "1" smd circle
			(at -0.40005 0 180)
			(size 0 0)
			(layers "F.Cu" "F.Mask" "F.Paste")
			(net "P3V3_AUX")
		)
		(pad "2" smd circle
			(at 0.40005 0 180)
			(size 0 0)
			(layers "F.Cu" "F.Mask" "F.Paste")
			(net "PU_PCH_VRALERT_N")
		)
	)
)
